# T6G (Grand Teton) — schematic netlist excerpt (pin names and nets, part order shuffled) for the footprints in the layout excerpt that follows; sources: Cadence DE-HDL packaged netlist, KiCad conversion of 04192023_DAF0TMB3IC0_F0TG_MB_C_brd_V02_OCP.brd

C837  Q_CAP_DIFFBUS  DIFF BUS_0.22UF 6.3V 20% X6S  pkg C0201  page 65 : \1\ = P5E_CPU1_P0_TX_C_DP<0> ; \2\ = P5E_CPU1_P0_TX_DP<0>
R3455  Q_RES  10K 1% CHIP  pkg 0402LF  page 128 : A = RST_PERST_2_SWB_BUF_R_N ; B = GND

(kicad_pcb
	(version 20260206)
	(generator "pcbnew")
	(generator_version "10.0")
	(general
		(thickness 1.6)
		(legacy_teardrops no)
	)
	(paper "A4")
	(title_block
		(title "04192023_DAF0TMB3IC0_F0TG_MB_C_brd_V02_OCP.brd")
		(comment 1 "Grand Teton / footprints 1191-1192 of 8354")
	)
	(layers
		(0 "F.Cu" signal "TOP")
		(4 "In1.Cu" signal "GND")
		(6 "In2.Cu" signal "IN1")
		(8 "In3.Cu" signal "GND1")
		(10 "In4.Cu" signal "IN2")
		(12 "In5.Cu" signal "GND2")
		(14 "In6.Cu" signal "IN3")
		(16 "In7.Cu" signal "GND3")
		(18 "In8.Cu" signal "VCC")
		(20 "In9.Cu" signal "VCC1")
		(22 "In10.Cu" signal "GND4")
		(24 "In11.Cu" signal "IN4")
		(26 "In12.Cu" signal "GND5")
		(28 "In13.Cu" signal "IN5")
		(30 "In14.Cu" signal "GND6")
		(32 "In15.Cu" signal "IN6")
		(34 "In16.Cu" signal "GND7")
		(2 "B.Cu" signal "BOTTOM")
		(9 "F.Adhes" user "F.Adhesive")
		(11 "B.Adhes" user "B.Adhesive")
		(13 "F.Paste" user "Package Geometry/Pastemask Top")
		(15 "B.Paste" user "Package Geometry/Pastemask Bottom")
		(5 "F.SilkS" user "Ref Des/Silkscreen Top")
		(7 "B.SilkS" user "Ref Des/Silkscreen Bottom")
		(1 "F.Mask" user "Board Geometry/Soldermask Top")
		(3 "B.Mask" user "Board Geometry/Soldermask Bottom")
		(17 "Dwgs.User" user "User.Drawings")
		(19 "Cmts.User" user "User.Comments")
		(21 "Eco1.User" user "User.Eco1")
		(23 "Eco2.User" user "User.Eco2")
		(25 "Edge.Cuts" user "Board Geometry/Outline")
		(27 "Margin" user)
		(31 "F.CrtYd" user "Package Geometry/Place Bound Top")
		(29 "B.CrtYd" user "Package Geometry/Place Bound Bottom")
		(35 "F.Fab" user "Ref Des/Assembly Top")
		(33 "B.Fab" user "Ref Des/Assembly Bottom")
	)
	(footprint ""
		(layer "F.Cu")
		(at 50.927 -433.578 180)
		(property "Reference" "R3455"
			(at 0 0 180)
			(layer "F.SilkS")
			(hide yes)
			(effects
				(font
					(size 1.27 1.27)
				)
			)
		)
		(property "Value" ""
			(at 0 0 180)
			(layer "F.Fab")
			(effects
				(font
					(size 1.27 1.27)
				)
			)
		)
		(duplicate_pad_numbers_are_jumpers no)
		(fp_line
			(start 0.7874 0.4064)
			(end -0.7874 0.4064)
			(stroke
				(width 0.1524)
				(type default)
			)
			(layer "F.SilkS")
		)
		(fp_line
			(start 0.7874 -0.4064)
			(end 0.7874 0.4064)
			(stroke
				(width 0.1524)
				(type default)
			)
			(layer "F.SilkS")
		)
		(fp_line
			(start -0.7874 0.4064)
			(end -0.7874 -0.4064)
			(stroke
				(width 0.1524)
				(type default)
			)
			(layer "F.SilkS")
		)
		(fp_line
			(start -0.7874 -0.4064)
			(end 0.7874 -0.4064)
			(stroke
				(width 0.1524)
				(type default)
			)
			(layer "F.SilkS")
		)
		(fp_line
			(start 0.67945 0.3048)
			(end 0.120396 0.3048)
			(stroke
				(width 0.1)
				(type default)
			)
			(layer "F.Fab")
		)
		(fp_line
			(start 0.67945 -0.3048)
			(end 0.67945 0.3048)
			(stroke
				(width 0.1)
				(type default)
			)
			(layer "F.Fab")
		)
		(fp_line
			(start 0.12065 -0.2794)
			(end 0.12065 -0.3048)
			(stroke
				(width 0.1)
				(type default)
			)
			(layer "F.Fab")
		)
		(fp_line
			(start 0.12065 -0.3048)
			(end 0.67945 -0.3048)
			(stroke
				(width 0.1)
				(type default)
			)
			(layer "F.Fab")
		)
		(fp_line
			(start 0.120396 0.3048)
			(end 0.120396 0.2794)
			(stroke
				(width 0.1)
				(type default)
			)
			(layer "F.Fab")
		)
		(fp_line
			(start 0.120396 0.2794)
			(end -0.12065 0.2794)
			(stroke
				(width 0.1)
				(type default)
			)
			(layer "F.Fab")
		)
		(fp_line
			(start -0.12065 0.3048)
			(end -0.67945 0.3048)
			(stroke
				(width 0.1)
				(type default)
			)
			(layer "F.Fab")
		)
		(fp_line
			(start -0.12065 0.2794)
			(end -0.12065 0.3048)
			(stroke
				(width 0.1)
				(type default)
			)
			(layer "F.Fab")
		)
		(fp_line
			(start -0.12065 -0.2794)
			(end 0.12065 -0.2794)
			(stroke
				(width 0.1)
				(type default)
			)
			(layer "F.Fab")
		)
		(fp_line
			(start -0.12065 -0.305054)
			(end -0.12065 -0.2794)
			(stroke
				(width 0.1)
				(type default)
			)
			(layer "F.Fab")
		)
		(fp_line
			(start -0.67945 0.3048)
			(end -0.67945 -0.305054)
			(stroke
				(width 0.1)
				(type default)
			)
			(layer "F.Fab")
		)
		(fp_line
			(start -0.67945 -0.305054)
			(end -0.12065 -0.305054)
			(stroke
				(width 0.1)
				(type default)
			)
			(layer "F.Fab")
		)
		(pad "1" smd circle
			(at -0.40005 0 180)
			(size 0 0)
			(layers "F.Cu" "F.Mask" "F.Paste")
			(net "RST_PERST_2_SWB_BUF_R_N")
		)
		(pad "2" smd circle
			(at 0.40005 0 180)
			(size 0 0)
			(layers "F.Cu" "F.Mask" "F.Paste")
			(net "GND")
		)
	)
	(footprint ""
		(layer "F.Cu")
		(at 42.967402 -382.39446 180)
		(property "Reference" "C837"
			(at 0 0 180)
			(layer "F.SilkS")
			(hide yes)
			(effects
				(font
					(size 1.27 1.27)
				)
			)
		)
		(property "Value" ""
			(at 0 0 180)
			(layer "F.Fab")
			(effects
				(font
					(size 1.27 1.27)
				)
			)
		)
		(duplicate_pad_numbers_are_jumpers no)
		(fp_line
			(start 0.299974 0.150114)
			(end -0.299974 0.150114)
			(stroke
				(width 0.1)
				(type default)
			)
			(layer "F.Fab")
		)
		(fp_line
			(start 0.299974 -0.150114)
			(end 0.299974 0.150114)
			(stroke
				(width 0.1)
				(type default)
			)
			(layer "F.Fab")
		)
		(fp_line
			(start -0.299974 0.150114)
			(end -0.299974 -0.150114)
			(stroke
				(width 0.1)
				(type default)
			)
			(layer "F.Fab")
		)
		(fp_line
			(start -0.299974 -0.150114)
			(end 0.299974 -0.150114)
			(stroke
				(width 0.1)
				(type default)
			)
			(layer "F.Fab")
		)
		(pad "1" smd rect
			(at -0.2667 0 180)
			(size 0.3048 0.381)
			(layers "F.Cu" "F.Mask" "F.Paste")
			(net "P5E_CPU1_P0_TX_C_DP<0>")
		)
		(pad "2" smd rect
			(at 0.2667 0 180)
			(size 0.3048 0.381)
			(layers "F.Cu" "F.Mask" "F.Paste")
			(net "P5E_CPU1_P0_TX_DP<0>")
		)
	)
)
